(kicad_pcb
	(version 20260206)
	(generator "pcbnew")
	(generator_version "10.0")
	(general
		(thickness 1.6)
		(legacy_teardrops no)
	)
	(paper "A4")
	(title_block
		(title "v2-tray-backplane — ms_tbp_v2.brd")
		(comment 1 "Open CloudServer (Microsoft) / footprints 116-122 of 164")
	)
	(layers
		(0 "F.Cu" signal "TOP")
		(4 "In1.Cu" signal "LYR2")
		(6 "In2.Cu" signal "LYR3")
		(8 "In3.Cu" signal "LYR4")
		(10 "In4.Cu" signal "LYR5")
		(12 "In5.Cu" signal "LYR6")
		(14 "In6.Cu" signal "LYR7")
		(2 "B.Cu" signal "BOTTOM")
		(9 "F.Adhes" user "F.Adhesive")
		(11 "B.Adhes" user "B.Adhesive")
		(13 "F.Paste" user "Package Geometry/Pastemask Top")
		(15 "B.Paste" user "Package Geometry/Pastemask Bottom")
		(5 "F.SilkS" user "Ref Des/Silkscreen Top")
		(7 "B.SilkS" user "Ref Des/Silkscreen Bottom")
		(1 "F.Mask" user "Board Geometry/Soldermask Top")
		(3 "B.Mask" user "Board Geometry/Soldermask Bottom")
		(17 "Dwgs.User" user "User.Drawings")
		(19 "Cmts.User" user "User.Comments")
		(21 "Eco1.User" user "User.Eco1")
		(23 "Eco2.User" user "User.Eco2")
		(25 "Edge.Cuts" user "Board Geometry/Outline")
		(27 "Margin" user)
		(31 "F.CrtYd" user "Package Geometry/Place Bound Top")
		(29 "B.CrtYd" user "Package Geometry/Place Bound Bottom")
		(35 "F.Fab" user "Ref Des/Assembly Top")
		(33 "B.Fab" user "Ref Des/Assembly Bottom")
	)
	(footprint ""
		(layer "F.Cu")
		(at -300.971801 4.635602 180)
		(property "Reference" "R25"
			(at 3.320199 0.025502 0)
			(unlocked yes)
			(layer "F.SilkS")
			(effects
				(font
					(size 0.762 0.5334)
					(thickness 0.1016)
				)
			)
		)
		(property "Value" ""
			(at 0 0 180)
			(layer "F.Fab")
			(effects
				(font
					(size 1.27 1.27)
				)
			)
		)
		(duplicate_pad_numbers_are_jumpers no)
		(fp_line
			(start 0 -0.381)
			(end 0 0.381)
			(stroke
				(width 0.127)
				(type default)
			)
			(layer "F.SilkS")
		)
		(fp_poly
			(pts
				(xy 1.255601 0.6564) (xy -1.255601 0.6564) (xy -1.255601 -0.656399) (xy 1.255601 -0.656399)
			)
			(stroke
				(width 0)
				(type default)
			)
			(fill no)
			(layer "F.CrtYd")
		)
		(fp_line
			(start 0.800001 0.4)
			(end 0.800001 -0.399999)
			(stroke
				(width 0.1)
				(type default)
			)
			(layer "F.Fab")
		)
		(fp_line
			(start 0.800001 -0.399999)
			(end -0.800001 -0.399999)
			(stroke
				(width 0.1)
				(type default)
			)
			(layer "F.Fab")
		)
		(fp_line
			(start -0.800001 0.4)
			(end 0.800001 0.4)
			(stroke
				(width 0.1)
				(type default)
			)
			(layer "F.Fab")
		)
		(fp_line
			(start -0.800001 -0.399999)
			(end -0.800001 0.4)
			(stroke
				(width 0.1)
				(type default)
			)
			(layer "F.Fab")
		)
		(pad "1" smd rect
			(at -0.650001 0 180)
			(size 0.7112 0.8128)
			(layers "F.Cu" "F.Mask" "F.Paste")
			(net "ETH10G_B1_RS1")
		)
		(pad "2" smd rect
			(at 0.650001 0)
			(size 0.7112 0.8128)
			(layers "F.Cu" "F.Mask" "F.Paste")
			(net "GND")
		)
	)
	(footprint ""
		(layer "F.Cu")
		(at -316.25 39.010001 180)
		(property "Reference" "J9"
			(at -8.27754 -8.708979 0)
			(unlocked yes)
			(layer "F.SilkS")
			(effects
				(font
					(size 0.762 0.5334)
					(thickness 0.1016)
				)
			)
		)
		(property "Value" ""
			(at 0 0 180)
			(layer "F.Fab")
			(effects
				(font
					(size 1.27 1.27)
				)
			)
		)
		(duplicate_pad_numbers_are_jumpers no)
		(fp_line
			(start 9.874999 50.85)
			(end 9.874999 34.000001)
			(stroke
				(width 0.127)
				(type default)
			)
			(layer "F.SilkS")
		)
		(fp_line
			(start 9.874999 25.000001)
			(end 9.874999 32)
			(stroke
				(width 0.127)
				(type default)
			)
			(layer "F.SilkS")
		)
		(fp_line
			(start 9.874999 16.000001)
			(end 9.874999 23)
			(stroke
				(width 0.127)
				(type default)
			)
			(layer "F.SilkS")
		)
		(fp_line
			(start 9.874999 7.000002)
			(end 9.874999 14)
			(stroke
				(width 0.127)
				(type default)
			)
			(layer "F.SilkS")
		)
		(fp_line
			(start 9.874999 -3.75)
			(end 9.874999 5)
			(stroke
				(width 0.127)
				(type default)
			)
			(layer "F.SilkS")
		)
		(fp_line
			(start -9.874999 50.85)
			(end 9.874999 50.85)
			(stroke
				(width 0.127)
				(type default)
			)
			(layer "F.SilkS")
		)
		(fp_line
			(start -9.874999 38.499999)
			(end -9.874999 50.85)
			(stroke
				(width 0.127)
				(type default)
			)
			(layer "F.SilkS")
		)
		(fp_line
			(start -9.874999 36.500001)
			(end -9.874999 29.5)
			(stroke
				(width 0.127)
				(type default)
			)
			(layer "F.SilkS")
		)
		(fp_line
			(start -9.874999 27.500001)
			(end -9.874999 20.5)
			(stroke
				(width 0.127)
				(type default)
			)
			(layer "F.SilkS")
		)
		(fp_line
			(start -9.874999 18.500001)
			(end -9.874999 11.5)
			(stroke
				(width 0.127)
				(type default)
			)
			(layer "F.SilkS")
		)
		(fp_line
			(start -9.874999 9.499999)
			(end -9.874999 0.750001)
			(stroke
				(width 0.127)
				(type default)
			)
			(layer "F.SilkS")
		)
		(fp_line
			(start -9.874999 -2.137999)
			(end -9.874999 -7.869999)
			(stroke
				(width 0.127)
				(type default)
			)
			(layer "F.SilkS")
		)
		(fp_line
			(start -9.874999 -7.869999)
			(end -6.074999 -7.869999)
			(stroke
				(width 0.127)
				(type default)
			)
			(layer "F.SilkS")
		)
		(fp_poly
			(pts
				(arc
					(start -4.199999 37.600001)
					(mid -9.703758 42.804115)
					(end -14.807001 37.2067)
				)
				(arc
					(start -14.807001 -0.1848)
					(mid -14.550292 -1.881885)
					(end -13.7654 -3.408299)
				)
				(arc
					(start -9.7682 -10.080899)
					(mid -7.846041 -12.229854)
					(end -5.084001 -13.056799)
				)
				(arc
					(start -5.0811 -13.056799)
					(mid -4.99375 -13.057419)
					(end -4.906401 -13.0566)
				)
				(arc
					(start 1.8942 -13.048599)
					(mid 3.117342 -12.977539)
					(end 4.291599 -12.627899)
				)
				(arc
					(start 10.9939 -9.842799)
					(mid 11.536623 -9.651121)
					(end 12.055399 -9.4018)
				)
				(arc
					(start 12.0555 -9.401701)
					(mid 14.088517 -7.41727)
					(end 14.8068 -4.668598)
				)
				(arc
					(start 14.8068 32.7031)
					(mid 10.110545 38.317137)
					(end 4.199999 34.000001)
				)
				(xy 4.199999 -2.5) (xy -4.199999 -2.5)
			)
			(stroke
				(width 0)
				(type default)
			)
			(fill no)
			(layer "B.CrtYd")
		)
		(fp_poly
			(pts
				(xy -10.875 51.850001)
				(arc
					(start -10.875 38.564599)
					(mid -11.270016 37.45)
					(end -10.875 36.335401)
				)
				(arc
					(start -10.875 29.5646)
					(mid -11.270017 28.450001)
					(end -10.875 27.335402)
				)
				(arc
					(start -10.875 20.5646)
					(mid -11.270017 19.449999)
					(end -10.875 18.335399)
				)
				(arc
					(start -10.875 11.5646)
					(mid -11.270016 10.45)
					(end -10.875 9.335399)
				)
				(arc
					(start -10.875 0.864601)
					(mid -11.270016 -0.249999)
					(end -10.875 -1.364599)
				)
				(xy -10.875 -8.87)
				(arc
					(start -6.370599 -8.87)
					(mid -5 -9.520011)
					(end -3.629401 -8.87)
				)
				(arc
					(start 0.829399 -8.87)
					(mid 2.2 -9.520014)
					(end 3.5706 -8.87)
				)
				(xy 10.875 -8.87)
				(arc
					(start 10.875 -5.864601)
					(mid 11.270017 -4.75)
					(end 10.875 -3.6354)
				)
				(arc
					(start 10.875 4.835401)
					(mid 11.270016 5.950001)
					(end 10.875 7.064601)
				)
				(arc
					(start 10.875 13.835401)
					(mid 11.270016 14.950001)
					(end 10.875 16.064601)
				)
				(arc
					(start 10.875 22.8354)
					(mid 11.270017 23.950001)
					(end 10.875 25.064601)
				)
				(arc
					(start 10.875 31.8354)
					(mid 11.270016 32.95)
					(end 10.875 34.064601)
				)
				(xy 10.875 51.850001)
			)
			(stroke
				(width 0)
				(type default)
			)
			(fill no)
			(layer "F.CrtYd")
		)
		(fp_line
			(start 9.874999 50.85)
			(end 9.874999 -7.869999)
			(stroke
				(width 0.1)
				(type default)
			)
			(layer "F.Fab")
		)
		(fp_line
			(start 9.874999 -7.869999)
			(end -9.874999 -7.869999)
			(stroke
				(width 0.1)
				(type default)
			)
			(layer "F.Fab")
		)
		(fp_line
			(start -9.874999 50.85)
			(end 9.874999 50.85)
			(stroke
				(width 0.1)
				(type default)
			)
			(layer "F.Fab")
		)
		(fp_line
			(start -9.874999 -7.869999)
			(end -9.874999 50.85)
			(stroke
				(width 0.1)
				(type default)
			)
			(layer "F.Fab")
		)
		(pad "1" thru_hole circle
			(at -9.499999 -0.25 270)
			(size 1.5494 1.5494)
			(drill 1.0414)
			(layers "*.Cu" "*.Mask")
			(remove_unused_layers no)
			(net "GND")
		)
		(pad "2" thru_hole circle
			(at -9.499999 10.449999 270)
			(size 1.5494 1.5494)
			(drill 1.0414)
			(layers "*.Cu" "*.Mask")
			(remove_unused_layers no)
			(net "GND")
		)
		(pad "3" thru_hole circle
			(at -9.499999 19.449999 270)
			(size 1.5494 1.5494)
			(drill 1.0414)
			(layers "*.Cu" "*.Mask")
			(remove_unused_layers no)
			(net "GND")
		)
		(pad "4" thru_hole circle
			(at -9.499999 28.449999 270)
			(size 1.5494 1.5494)
			(drill 1.0414)
			(layers "*.Cu" "*.Mask")
			(remove_unused_layers no)
			(net "GND")
		)
		(pad "5" thru_hole circle
			(at -9.499999 37.449999 270)
			(size 1.5494 1.5494)
			(drill 1.0414)
			(layers "*.Cu" "*.Mask")
			(remove_unused_layers no)
			(net "GND")
		)
		(pad "6" thru_hole circle
			(at -5 -7.75 270)
			(size 1.5494 1.5494)
			(drill 1.0414)
			(layers "*.Cu" "*.Mask")
			(remove_unused_layers no)
			(net "GND")
		)
		(pad "7" thru_hole circle
			(at 2.200001 -7.75 270)
			(size 1.5494 1.5494)
			(drill 1.0414)
			(layers "*.Cu" "*.Mask")
			(remove_unused_layers no)
			(net "GND")
		)
		(pad "8" thru_hole circle
			(at 9.499999 -4.750001 270)
			(size 1.5494 1.5494)
			(drill 1.0414)
			(layers "*.Cu" "*.Mask")
			(remove_unused_layers no)
			(net "GND")
		)
		(pad "9" thru_hole circle
			(at 9.499999 5.950001 270)
			(size 1.5494 1.5494)
			(drill 1.0414)
			(layers "*.Cu" "*.Mask")
			(remove_unused_layers no)
			(net "GND")
		)
		(pad "10" thru_hole circle
			(at 9.499999 14.950001 270)
			(size 1.5494 1.5494)
			(drill 1.0414)
			(layers "*.Cu" "*.Mask")
			(remove_unused_layers no)
			(net "GND")
		)
		(pad "11" thru_hole circle
			(at 9.499999 23.95 270)
			(size 1.5494 1.5494)
			(drill 1.0414)
			(layers "*.Cu" "*.Mask")
			(remove_unused_layers no)
			(net "GND")
		)
		(pad "12" thru_hole circle
			(at 9.499999 32.95 270)
			(size 1.5494 1.5494)
			(drill 1.0414)
			(layers "*.Cu" "*.Mask")
			(remove_unused_layers no)
			(net "GND")
		)
	)
	(footprint ""
		(layer "F.Cu")
		(at -115.423 4.9276 -90)
		(property "Reference" "R37"
			(at 1.84404 -1.1611 90)
			(unlocked yes)
			(layer "F.SilkS")
			(effects
				(font
					(size 0.762 0.5334)
					(thickness 0.1016)
				)
			)
		)
		(property "Value" ""
			(at 0 0 270)
			(layer "F.Fab")
			(effects
				(font
					(size 1.27 1.27)
				)
			)
		)
		(duplicate_pad_numbers_are_jumpers no)
		(fp_line
			(start 0 -0.381)
			(end 0 0.381)
			(stroke
				(width 0.127)
				(type default)
			)
			(layer "F.SilkS")
		)
		(fp_poly
			(pts
				(xy 1.255601 0.6564) (xy -1.255601 0.6564) (xy -1.255601 -0.656399) (xy 1.255601 -0.656399)
			)
			(stroke
				(width 0)
				(type default)
			)
			(fill no)
			(layer "F.CrtYd")
		)
		(fp_line
			(start -0.800001 0.399999)
			(end 0.800001 0.399999)
			(stroke
				(width 0.1)
				(type default)
			)
			(layer "F.Fab")
		)
		(fp_line
			(start 0.800001 0.399999)
			(end 0.800001 -0.399999)
			(stroke
				(width 0.1)
				(type default)
			)
			(layer "F.Fab")
		)
		(fp_line
			(start -0.800001 -0.399999)
			(end -0.800001 0.399999)
			(stroke
				(width 0.1)
				(type default)
			)
			(layer "F.Fab")
		)
		(fp_line
			(start 0.800001 -0.399999)
			(end -0.800001 -0.399999)
			(stroke
				(width 0.1)
				(type default)
			)
			(layer "F.Fab")
		)
		(pad "1" smd rect
			(at -0.650001 0 270)
			(size 0.7112 0.8128)
			(layers "F.Cu" "F.Mask" "F.Paste")
			(net "UNNAMED_6_1X2HDR_I52_IO")
		)
		(pad "2" smd rect
			(at 0.650001 0 90)
			(size 0.7112 0.8128)
			(layers "F.Cu" "F.Mask" "F.Paste")
			(net "GND")
		)
	)
	(footprint ""
		(layer "F.Cu")
		(at -331.47 13.2588)
		(property "Reference" "R76"
			(at 3.175 -0.0127 0)
			(unlocked yes)
			(layer "F.SilkS")
			(effects
				(font
					(size 0.762 0.5334)
					(thickness 0.1016)
				)
			)
		)
		(property "Value" ""
			(at 0 0 0)
			(layer "F.Fab")
			(effects
				(font
					(size 1.27 1.27)
				)
			)
		)
		(duplicate_pad_numbers_are_jumpers no)
		(fp_line
			(start 0 -0.381)
			(end 0 0.381)
			(stroke
				(width 0.127)
				(type default)
			)
			(layer "F.SilkS")
		)
		(fp_poly
			(pts
				(xy 1.255601 0.6564) (xy -1.255601 0.6564) (xy -1.255601 -0.656399) (xy 1.255601 -0.656399)
			)
			(stroke
				(width 0)
				(type default)
			)
			(fill no)
			(layer "F.CrtYd")
		)
		(fp_line
			(start -0.800001 -0.399999)
			(end -0.800001 0.399999)
			(stroke
				(width 0.1)
				(type default)
			)
			(layer "F.Fab")
		)
		(fp_line
			(start -0.800001 0.399999)
			(end 0.800001 0.399999)
			(stroke
				(width 0.1)
				(type default)
			)
			(layer "F.Fab")
		)
		(fp_line
			(start 0.800001 -0.399999)
			(end -0.800001 -0.399999)
			(stroke
				(width 0.1)
				(type default)
			)
			(layer "F.Fab")
		)
		(fp_line
			(start 0.800001 0.399999)
			(end 0.800001 -0.399999)
			(stroke
				(width 0.1)
				(type default)
			)
			(layer "F.Fab")
		)
		(pad "1" smd rect
			(at -0.650001 0)
			(size 0.7112 0.8128)
			(layers "F.Cu" "F.Mask" "F.Paste")
			(net "P3V3_B1_QSFP")
		)
		(pad "2" smd rect
			(at 0.650001 0 180)
			(size 0.7112 0.8128)
			(layers "F.Cu" "F.Mask" "F.Paste")
			(net "ETH40G_B1_MODSEL_N")
		)
	)
	(footprint ""
		(layer "F.Cu")
		(at -418.06 42.660001)
		(property "Reference" "MH1"
			(at 0.0522 -4.725101 0)
			(unlocked yes)
			(layer "F.SilkS")
			(effects
				(font
					(size 0.762 0.5334)
					(thickness 0.1016)
				)
			)
		)
		(property "Value" ""
			(at 0 0 0)
			(layer "F.Fab")
			(effects
				(font
					(size 1.27 1.27)
				)
			)
		)
		(duplicate_pad_numbers_are_jumpers no)
		(fp_poly
			(pts
				(arc
					(start 4.0132 0)
					(mid -4.0132 0)
					(end 4.0132 0)
				)
			)
			(stroke
				(width 0)
				(type default)
			)
			(fill no)
			(layer "B.CrtYd")
		)
		(fp_poly
			(pts
				(arc
					(start 4.0132 0)
					(mid -4.0132 0)
					(end 4.0132 0)
				)
			)
			(stroke
				(width 0)
				(type default)
			)
			(fill no)
			(layer "F.CrtYd")
		)
		(pad "1" thru_hole circle
			(at 0 0)
			(size 7.0104 7.0104)
			(drill 3.5052)
			(layers "*.Cu" "*.Mask")
			(remove_unused_layers no)
			(net "GND")
			(padstack
				(mode front_inner_back)
				(layer "Inner"
					(shape circle)
					(size 4.5212 4.5212)
				)
				(layer "B.Cu"
					(shape circle)
					(size 7.0104 7.0104)
				)
			)
		)
		(pad "2" thru_hole circle
			(at 0 -2.794)
			(size 0.6604 0.6604)
			(drill 0.3556)
			(layers "*.Cu" "*.Mask")
			(remove_unused_layers no)
			(net "GND")
		)
		(pad "3" thru_hole circle
			(at -1.905 -2.032)
			(size 0.6604 0.6604)
			(drill 0.3556)
			(layers "*.Cu" "*.Mask")
			(remove_unused_layers no)
			(net "GND")
		)
		(pad "4" thru_hole circle
			(at -2.794 0)
			(size 0.6604 0.6604)
			(drill 0.3556)
			(layers "*.Cu" "*.Mask")
			(remove_unused_layers no)
			(net "GND")
		)
		(pad "5" thru_hole circle
			(at -2.032 1.905)
			(size 0.6604 0.6604)
			(drill 0.3556)
			(layers "*.Cu" "*.Mask")
			(remove_unused_layers no)
			(net "GND")
		)
		(pad "6" thru_hole circle
			(at 0 2.794)
			(size 0.6604 0.6604)
			(drill 0.3556)
			(layers "*.Cu" "*.Mask")
			(remove_unused_layers no)
			(net "GND")
		)
		(pad "7" thru_hole circle
			(at 2.032 1.905)
			(size 0.6604 0.6604)
			(drill 0.3556)
			(layers "*.Cu" "*.Mask")
			(remove_unused_layers no)
			(net "GND")
		)
		(pad "8" thru_hole circle
			(at 2.794 0)
			(size 0.6604 0.6604)
			(drill 0.3556)
			(layers "*.Cu" "*.Mask")
			(remove_unused_layers no)
			(net "GND")
		)
		(pad "9" thru_hole circle
			(at 1.905 -2.032)
			(size 0.6604 0.6604)
			(drill 0.3556)
			(layers "*.Cu" "*.Mask")
			(remove_unused_layers no)
			(net "GND")
		)
	)
	(footprint ""
		(layer "F.Cu")
		(at -386.773001 39.357399)
		(property "Reference" "MH2"
			(at 0 -4.9149 0)
			(unlocked yes)
			(layer "F.SilkS")
			(effects
				(font
					(size 0.762 0.5334)
					(thickness 0.1016)
				)
			)
		)
		(property "Value" ""
			(at 0 0 0)
			(layer "F.Fab")
			(effects
				(font
					(size 1.27 1.27)
				)
			)
		)
		(duplicate_pad_numbers_are_jumpers no)
		(fp_poly
			(pts
				(arc
					(start 4.0132 0)
					(mid -4.0132 0)
					(end 4.0132 0)
				)
			)
			(stroke
				(width 0)
				(type default)
			)
			(fill no)
			(layer "B.CrtYd")
		)
		(fp_poly
			(pts
				(arc
					(start 4.0132 0)
					(mid -4.0132 0)
					(end 4.0132 0)
				)
			)
			(stroke
				(width 0)
				(type default)
			)
			(fill no)
			(layer "F.CrtYd")
		)
		(pad "1" thru_hole circle
			(at 0 0)
			(size 7.0104 7.0104)
			(drill 3.5052)
			(layers "*.Cu" "*.Mask")
			(remove_unused_layers no)
			(net "GND")
			(padstack
				(mode front_inner_back)
				(layer "Inner"
					(shape circle)
					(size 4.5212 4.5212)
				)
				(layer "B.Cu"
					(shape circle)
					(size 7.0104 7.0104)
				)
			)
		)
		(pad "2" thru_hole circle
			(at 0 -2.794)
			(size 0.6604 0.6604)
			(drill 0.3556)
			(layers "*.Cu" "*.Mask")
			(remove_unused_layers no)
			(net "GND")
		)
		(pad "3" thru_hole circle
			(at -1.905 -2.032)
			(size 0.6604 0.6604)
			(drill 0.3556)
			(layers "*.Cu" "*.Mask")
			(remove_unused_layers no)
			(net "GND")
		)
		(pad "4" thru_hole circle
			(at -2.794 0)
			(size 0.6604 0.6604)
			(drill 0.3556)
			(layers "*.Cu" "*.Mask")
			(remove_unused_layers no)
			(net "GND")
		)
		(pad "5" thru_hole circle
			(at -2.032 1.905)
			(size 0.6604 0.6604)
			(drill 0.3556)
			(layers "*.Cu" "*.Mask")
			(remove_unused_layers no)
			(net "GND")
		)
		(pad "6" thru_hole circle
			(at 0 2.794)
			(size 0.6604 0.6604)
			(drill 0.3556)
			(layers "*.Cu" "*.Mask")
			(remove_unused_layers no)
			(net "GND")
		)
		(pad "7" thru_hole circle
			(at 2.032 1.905)
			(size 0.6604 0.6604)
			(drill 0.3556)
			(layers "*.Cu" "*.Mask")
			(remove_unused_layers no)
			(net "GND")
		)
		(pad "8" thru_hole circle
			(at 2.794 0)
			(size 0.6604 0.6604)
			(drill 0.3556)
			(layers "*.Cu" "*.Mask")
			(remove_unused_layers no)
			(net "GND")
		)
		(pad "9" thru_hole circle
			(at 1.905 -2.032)
			(size 0.6604 0.6604)
			(drill 0.3556)
			(layers "*.Cu" "*.Mask")
			(remove_unused_layers no)
			(net "GND")
		)
	)
	(footprint ""
		(layer "F.Cu")
		(at -58.610401 44.488202)
		(property "Reference" "C10"
			(at 2.603401 -0.000102 0)
			(unlocked yes)
			(layer "F.SilkS")
			(effects
				(font
					(size 0.762 0.5334)
					(thickness 0.1016)
				)
			)
		)
		(property "Value" ""
			(at 0 0 0)
			(layer "F.Fab")
			(effects
				(font
					(size 1.27 1.27)
				)
			)
		)
		(duplicate_pad_numbers_are_jumpers no)
		(fp_poly
			(pts
				(xy -0.999299 0.503999) (xy -0.999299 -0.504) (xy 0.9993 -0.504) (xy 0.9993 0.503999)
			)
			(stroke
				(width 0)
				(type default)
			)
			(fill no)
			(layer "F.CrtYd")
		)
		(fp_line
			(start -0.499999 -0.25)
			(end 0.499999 -0.25)
			(stroke
				(width 0.1)
				(type default)
			)
			(layer "F.Fab")
		)
		(fp_line
			(start -0.499999 0.249999)
			(end -0.499999 -0.25)
			(stroke
				(width 0.1)
				(type default)
			)
			(layer "F.Fab")
		)
		(fp_line
			(start 0.499999 -0.25)
			(end 0.499999 0.249999)
			(stroke
				(width 0.1)
				(type default)
			)
			(layer "F.Fab")
		)
		(fp_line
			(start 0.499999 0.249999)
			(end -0.499999 0.249999)
			(stroke
				(width 0.1)
				(type default)
			)
			(layer "F.Fab")
		)
		(pad "1" smd rect
			(at -0.4572 0 90)
			(size 0.508 0.5842)
			(layers "F.Cu" "F.Mask" "F.Paste")
			(net "P3V3_10G_B2_VCCT")
		)
		(pad "2" smd rect
			(at 0.4572 0 90)
			(size 0.508 0.5842)
			(layers "F.Cu" "F.Mask" "F.Paste")
			(net "GND")
		)
	)
)
